(kicad_pcb
	(version 20260206)
	(generator "pcbnew")
	(generator_version "10.0")
	(general
		(thickness 1.6)
		(legacy_teardrops no)
	)
	(paper "A4")
	(title_block
		(title "01162023_DA0F0TEBIF0_F0T_Expander_BD_F_brd_V02_OCP.brd")
		(comment 1 "Grand Teton / footprints 243-248 of 9728")
	)
	(layers
		(0 "F.Cu" signal "TOP")
		(4 "In1.Cu" signal "GND")
		(6 "In2.Cu" signal "VCC")
		(8 "In3.Cu" signal "VCC1")
		(10 "In4.Cu" signal "GND1")
		(12 "In5.Cu" signal "IN1")
		(14 "In6.Cu" signal "GND2")
		(16 "In7.Cu" signal "IN2")
		(18 "In8.Cu" signal "GND3")
		(20 "In9.Cu" signal "IN3")
		(22 "In10.Cu" signal "GND4")
		(24 "In11.Cu" signal "IN4")
		(26 "In12.Cu" signal "GND5")
		(28 "In13.Cu" signal "IN5")
		(30 "In14.Cu" signal "GND6")
		(32 "In15.Cu" signal "IN6")
		(34 "In16.Cu" signal "GND7")
		(2 "B.Cu" signal "BOTTOM")
		(9 "F.Adhes" user "F.Adhesive")
		(11 "B.Adhes" user "B.Adhesive")
		(13 "F.Paste" user "Package Geometry/Pastemask Top")
		(15 "B.Paste" user "Package Geometry/Pastemask Bottom")
		(5 "F.SilkS" user "Ref Des/Silkscreen Top")
		(7 "B.SilkS" user "Ref Des/Silkscreen Bottom")
		(1 "F.Mask" user "Board Geometry/Soldermask Top")
		(3 "B.Mask" user "Board Geometry/Soldermask Bottom")
		(17 "Dwgs.User" user "User.Drawings")
		(19 "Cmts.User" user "User.Comments")
		(21 "Eco1.User" user "User.Eco1")
		(23 "Eco2.User" user "User.Eco2")
		(25 "Edge.Cuts" user "Board Geometry/Outline")
		(27 "Margin" user)
		(31 "F.CrtYd" user "Package Geometry/Place Bound Top")
		(29 "B.CrtYd" user "Package Geometry/Place Bound Bottom")
		(35 "F.Fab" user "Ref Des/Assembly Top")
		(33 "B.Fab" user "Ref Des/Assembly Bottom")
	)
	(footprint ""
		(layer "F.Cu")
		(at 371.690392 -236.953298)
		(property "Reference" "R6404"
			(at 0 0 0)
			(layer "F.SilkS")
			(hide yes)
			(effects
				(font
					(size 1.27 1.27)
				)
			)
		)
		(property "Value" ""
			(at 0 0 0)
			(layer "F.Fab")
			(effects
				(font
					(size 1.27 1.27)
				)
			)
		)
		(duplicate_pad_numbers_are_jumpers no)
		(fp_line
			(start -0.7874 -0.4064)
			(end 0.7874 -0.4064)
			(stroke
				(width 0.1524)
				(type default)
			)
			(layer "F.SilkS")
		)
		(fp_line
			(start -0.7874 0.4064)
			(end -0.7874 -0.4064)
			(stroke
				(width 0.1524)
				(type default)
			)
			(layer "F.SilkS")
		)
		(fp_line
			(start 0.7874 -0.4064)
			(end 0.7874 0.4064)
			(stroke
				(width 0.1524)
				(type default)
			)
			(layer "F.SilkS")
		)
		(fp_line
			(start 0.7874 0.4064)
			(end -0.7874 0.4064)
			(stroke
				(width 0.1524)
				(type default)
			)
			(layer "F.SilkS")
		)
		(fp_line
			(start -0.67945 -0.305054)
			(end -0.12065 -0.305054)
			(stroke
				(width 0.1)
				(type default)
			)
			(layer "F.Fab")
		)
		(fp_line
			(start -0.67945 0.3048)
			(end -0.67945 -0.305054)
			(stroke
				(width 0.1)
				(type default)
			)
			(layer "F.Fab")
		)
		(fp_line
			(start -0.12065 -0.305054)
			(end -0.12065 -0.2794)
			(stroke
				(width 0.1)
				(type default)
			)
			(layer "F.Fab")
		)
		(fp_line
			(start -0.12065 -0.2794)
			(end 0.12065 -0.2794)
			(stroke
				(width 0.1)
				(type default)
			)
			(layer "F.Fab")
		)
		(fp_line
			(start -0.12065 0.2794)
			(end -0.12065 0.3048)
			(stroke
				(width 0.1)
				(type default)
			)
			(layer "F.Fab")
		)
		(fp_line
			(start -0.12065 0.3048)
			(end -0.67945 0.3048)
			(stroke
				(width 0.1)
				(type default)
			)
			(layer "F.Fab")
		)
		(fp_line
			(start 0.120396 0.2794)
			(end -0.12065 0.2794)
			(stroke
				(width 0.1)
				(type default)
			)
			(layer "F.Fab")
		)
		(fp_line
			(start 0.120396 0.3048)
			(end 0.120396 0.2794)
			(stroke
				(width 0.1)
				(type default)
			)
			(layer "F.Fab")
		)
		(fp_line
			(start 0.12065 -0.3048)
			(end 0.67945 -0.3048)
			(stroke
				(width 0.1)
				(type default)
			)
			(layer "F.Fab")
		)
		(fp_line
			(start 0.12065 -0.2794)
			(end 0.12065 -0.3048)
			(stroke
				(width 0.1)
				(type default)
			)
			(layer "F.Fab")
		)
		(fp_line
			(start 0.67945 -0.3048)
			(end 0.67945 0.3048)
			(stroke
				(width 0.1)
				(type default)
			)
			(layer "F.Fab")
		)
		(fp_line
			(start 0.67945 0.3048)
			(end 0.120396 0.3048)
			(stroke
				(width 0.1)
				(type default)
			)
			(layer "F.Fab")
		)
		(pad "1" smd circle
			(at -0.40005 0)
			(size 0 0)
			(layers "F.Cu" "F.Mask" "F.Paste")
			(net "PWRGD_P5V_AUX_BUF")
		)
		(pad "2" smd circle
			(at 0.40005 0)
			(size 0 0)
			(layers "F.Cu" "F.Mask" "F.Paste")
			(net "PWRGD_P5V_AUX_BUF_R")
		)
	)
	(footprint ""
		(layer "F.Cu")
		(at 117.119654 -320.820034 90)
		(property "Reference" "C4217"
			(at 0 0 90)
			(layer "F.SilkS")
			(hide yes)
			(effects
				(font
					(size 1.27 1.27)
				)
			)
		)
		(property "Value" ""
			(at 0 0 90)
			(layer "F.Fab")
			(effects
				(font
					(size 1.27 1.27)
				)
			)
		)
		(duplicate_pad_numbers_are_jumpers no)
		(fp_line
			(start 1.2954 -0.5842)
			(end 1.2954 0.5842)
			(stroke
				(width 0.1524)
				(type default)
			)
			(layer "F.SilkS")
		)
		(fp_line
			(start -1.2954 -0.5842)
			(end 1.2954 -0.5842)
			(stroke
				(width 0.1524)
				(type default)
			)
			(layer "F.SilkS")
		)
		(fp_line
			(start 1.2954 0.5842)
			(end -1.2954 0.5842)
			(stroke
				(width 0.1524)
				(type default)
			)
			(layer "F.SilkS")
		)
		(fp_line
			(start -1.2954 0.5842)
			(end -1.2954 -0.5842)
			(stroke
				(width 0.1524)
				(type default)
			)
			(layer "F.SilkS")
		)
		(fp_line
			(start 0.8636 -0.4572)
			(end 0.8636 -0.4064)
			(stroke
				(width 0.1)
				(type default)
			)
			(layer "F.Fab")
		)
		(fp_line
			(start -0.8636 -0.4572)
			(end 0.8636 -0.4572)
			(stroke
				(width 0.1)
				(type default)
			)
			(layer "F.Fab")
		)
		(fp_line
			(start 1.1938 -0.4064)
			(end 1.1938 0.4064)
			(stroke
				(width 0.1)
				(type default)
			)
			(layer "F.Fab")
		)
		(fp_line
			(start 0.8636 -0.4064)
			(end 1.1938 -0.4064)
			(stroke
				(width 0.1)
				(type default)
			)
			(layer "F.Fab")
		)
		(fp_line
			(start -0.8636 -0.4064)
			(end -0.8636 -0.4572)
			(stroke
				(width 0.1)
				(type default)
			)
			(layer "F.Fab")
		)
		(fp_line
			(start -1.1938 -0.4064)
			(end -0.8636 -0.4064)
			(stroke
				(width 0.1)
				(type default)
			)
			(layer "F.Fab")
		)
		(fp_line
			(start 1.1938 0.4064)
			(end 0.8636 0.4064)
			(stroke
				(width 0.1)
				(type default)
			)
			(layer "F.Fab")
		)
		(fp_line
			(start 0.8636 0.4064)
			(end 0.8636 0.4572)
			(stroke
				(width 0.1)
				(type default)
			)
			(layer "F.Fab")
		)
		(fp_line
			(start -0.8636 0.4064)
			(end -1.1938 0.4064)
			(stroke
				(width 0.1)
				(type default)
			)
			(layer "F.Fab")
		)
		(fp_line
			(start -1.1938 0.4064)
			(end -1.1938 -0.4064)
			(stroke
				(width 0.1)
				(type default)
			)
			(layer "F.Fab")
		)
		(fp_line
			(start 0.8636 0.4572)
			(end -0.8636 0.4572)
			(stroke
				(width 0.1)
				(type default)
			)
			(layer "F.Fab")
		)
		(fp_line
			(start -0.8636 0.4572)
			(end -0.8636 0.4064)
			(stroke
				(width 0.1)
				(type default)
			)
			(layer "F.Fab")
		)
		(pad "1" smd rect
			(at -0.7366 0)
			(size 0.7112 0.8128)
			(layers "F.Cu" "F.Mask" "F.Paste")
			(net "P0V8_SERDES_VDDA_PEX0_C11")
		)
		(pad "2" smd rect
			(at 0.7366 0)
			(size 0.7112 0.8128)
			(layers "F.Cu" "F.Mask" "F.Paste")
			(net "GND")
		)
	)
	(footprint ""
		(layer "F.Cu")
		(at 374.015 -246.888)
		(property "Reference" "C2607"
			(at 0 0 0)
			(layer "F.SilkS")
			(hide yes)
			(effects
				(font
					(size 1.27 1.27)
				)
			)
		)
		(property "Value" ""
			(at 0 0 0)
			(layer "F.Fab")
			(effects
				(font
					(size 1.27 1.27)
				)
			)
		)
		(duplicate_pad_numbers_are_jumpers no)
		(fp_line
			(start -0.7874 -0.4064)
			(end 0.7874 -0.4064)
			(stroke
				(width 0.1524)
				(type default)
			)
			(layer "F.SilkS")
		)
		(fp_line
			(start -0.7874 0.4064)
			(end -0.7874 -0.4064)
			(stroke
				(width 0.1524)
				(type default)
			)
			(layer "F.SilkS")
		)
		(fp_line
			(start 0.7874 -0.4064)
			(end 0.7874 0.4064)
			(stroke
				(width 0.1524)
				(type default)
			)
			(layer "F.SilkS")
		)
		(fp_line
			(start 0.7874 0.4064)
			(end -0.7874 0.4064)
			(stroke
				(width 0.1524)
				(type default)
			)
			(layer "F.SilkS")
		)
		(fp_line
			(start -0.67945 -0.305054)
			(end -0.12065 -0.305054)
			(stroke
				(width 0.1)
				(type default)
			)
			(layer "F.Fab")
		)
		(fp_line
			(start -0.67945 0.3048)
			(end -0.67945 -0.305054)
			(stroke
				(width 0.1)
				(type default)
			)
			(layer "F.Fab")
		)
		(fp_line
			(start -0.12065 -0.305054)
			(end -0.12065 -0.2794)
			(stroke
				(width 0.1)
				(type default)
			)
			(layer "F.Fab")
		)
		(fp_line
			(start -0.12065 -0.2794)
			(end 0.12065 -0.2794)
			(stroke
				(width 0.1)
				(type default)
			)
			(layer "F.Fab")
		)
		(fp_line
			(start -0.12065 0.2794)
			(end -0.12065 0.3048)
			(stroke
				(width 0.1)
				(type default)
			)
			(layer "F.Fab")
		)
		(fp_line
			(start -0.12065 0.3048)
			(end -0.67945 0.3048)
			(stroke
				(width 0.1)
				(type default)
			)
			(layer "F.Fab")
		)
		(fp_line
			(start 0.120396 0.2794)
			(end -0.12065 0.2794)
			(stroke
				(width 0.1)
				(type default)
			)
			(layer "F.Fab")
		)
		(fp_line
			(start 0.120396 0.3048)
			(end 0.120396 0.2794)
			(stroke
				(width 0.1)
				(type default)
			)
			(layer "F.Fab")
		)
		(fp_line
			(start 0.12065 -0.3048)
			(end 0.67945 -0.3048)
			(stroke
				(width 0.1)
				(type default)
			)
			(layer "F.Fab")
		)
		(fp_line
			(start 0.12065 -0.2794)
			(end 0.12065 -0.3048)
			(stroke
				(width 0.1)
				(type default)
			)
			(layer "F.Fab")
		)
		(fp_line
			(start 0.67945 -0.3048)
			(end 0.67945 0.3048)
			(stroke
				(width 0.1)
				(type default)
			)
			(layer "F.Fab")
		)
		(fp_line
			(start 0.67945 0.3048)
			(end 0.120396 0.3048)
			(stroke
				(width 0.1)
				(type default)
			)
			(layer "F.Fab")
		)
		(pad "1" smd circle
			(at -0.40005 0)
			(size 0 0)
			(layers "F.Cu" "F.Mask" "F.Paste")
			(net "GND")
		)
		(pad "2" smd circle
			(at 0.40005 0)
			(size 0 0)
			(layers "F.Cu" "F.Mask" "F.Paste")
			(net "P1V8_PEX")
		)
	)
	(footprint ""
		(layer "F.Cu")
		(at 334.990186 -10.534142 -90)
		(property "Reference" "R1710"
			(at 0 0 270)
			(layer "F.SilkS")
			(hide yes)
			(effects
				(font
					(size 1.27 1.27)
				)
			)
		)
		(property "Value" ""
			(at 0 0 270)
			(layer "F.Fab")
			(effects
				(font
					(size 1.27 1.27)
				)
			)
		)
		(duplicate_pad_numbers_are_jumpers no)
		(fp_line
			(start -0.7874 0.4064)
			(end -0.7874 -0.4064)
			(stroke
				(width 0.1524)
				(type default)
			)
			(layer "F.SilkS")
		)
		(fp_line
			(start 0.7874 0.4064)
			(end -0.7874 0.4064)
			(stroke
				(width 0.1524)
				(type default)
			)
			(layer "F.SilkS")
		)
		(fp_line
			(start -0.7874 -0.4064)
			(end 0.7874 -0.4064)
			(stroke
				(width 0.1524)
				(type default)
			)
			(layer "F.SilkS")
		)
		(fp_line
			(start 0.7874 -0.4064)
			(end 0.7874 0.4064)
			(stroke
				(width 0.1524)
				(type default)
			)
			(layer "F.SilkS")
		)
		(fp_line
			(start -0.67945 0.3048)
			(end -0.67945 -0.305054)
			(stroke
				(width 0.1)
				(type default)
			)
			(layer "F.Fab")
		)
		(fp_line
			(start -0.12065 0.3048)
			(end -0.67945 0.3048)
			(stroke
				(width 0.1)
				(type default)
			)
			(layer "F.Fab")
		)
		(fp_line
			(start 0.120396 0.3048)
			(end 0.120396 0.2794)
			(stroke
				(width 0.1)
				(type default)
			)
			(layer "F.Fab")
		)
		(fp_line
			(start 0.67945 0.3048)
			(end 0.120396 0.3048)
			(stroke
				(width 0.1)
				(type default)
			)
			(layer "F.Fab")
		)
		(fp_line
			(start -0.12065 0.2794)
			(end -0.12065 0.3048)
			(stroke
				(width 0.1)
				(type default)
			)
			(layer "F.Fab")
		)
		(fp_line
			(start 0.120396 0.2794)
			(end -0.12065 0.2794)
			(stroke
				(width 0.1)
				(type default)
			)
			(layer "F.Fab")
		)
		(fp_line
			(start -0.12065 -0.2794)
			(end 0.12065 -0.2794)
			(stroke
				(width 0.1)
				(type default)
			)
			(layer "F.Fab")
		)
		(fp_line
			(start 0.12065 -0.2794)
			(end 0.12065 -0.3048)
			(stroke
				(width 0.1)
				(type default)
			)
			(layer "F.Fab")
		)
		(fp_line
			(start 0.12065 -0.3048)
			(end 0.67945 -0.3048)
			(stroke
				(width 0.1)
				(type default)
			)
			(layer "F.Fab")
		)
		(fp_line
			(start 0.67945 -0.3048)
			(end 0.67945 0.3048)
			(stroke
				(width 0.1)
				(type default)
			)
			(layer "F.Fab")
		)
		(fp_line
			(start -0.67945 -0.305054)
			(end -0.12065 -0.305054)
			(stroke
				(width 0.1)
				(type default)
			)
			(layer "F.Fab")
		)
		(fp_line
			(start -0.12065 -0.305054)
			(end -0.12065 -0.2794)
			(stroke
				(width 0.1)
				(type default)
			)
			(layer "F.Fab")
		)
		(pad "1" smd circle
			(at -0.40005 0 270)
			(size 0 0)
			(layers "F.Cu" "F.Mask" "F.Paste")
			(net "SMB_ISO_SSD11_R_SDA")
		)
		(pad "2" smd circle
			(at 0.40005 0 270)
			(size 0 0)
			(layers "F.Cu" "F.Mask" "F.Paste")
			(net "SMB_ISO_SSD11_SDA")
		)
	)
	(footprint ""
		(layer "F.Cu")
		(at 266.702286 -250.070874 -90)
		(property "Reference" "R1347"
			(at 0 0 270)
			(layer "F.SilkS")
			(hide yes)
			(effects
				(font
					(size 1.27 1.27)
				)
			)
		)
		(property "Value" ""
			(at 0 0 270)
			(layer "F.Fab")
			(effects
				(font
					(size 1.27 1.27)
				)
			)
		)
		(duplicate_pad_numbers_are_jumpers no)
		(fp_line
			(start -0.7874 0.4064)
			(end -0.7874 -0.4064)
			(stroke
				(width 0.1524)
				(type default)
			)
			(layer "F.SilkS")
		)
		(fp_line
			(start 0.7874 0.4064)
			(end -0.7874 0.4064)
			(stroke
				(width 0.1524)
				(type default)
			)
			(layer "F.SilkS")
		)
		(fp_line
			(start -0.7874 -0.4064)
			(end 0.7874 -0.4064)
			(stroke
				(width 0.1524)
				(type default)
			)
			(layer "F.SilkS")
		)
		(fp_line
			(start 0.7874 -0.4064)
			(end 0.7874 0.4064)
			(stroke
				(width 0.1524)
				(type default)
			)
			(layer "F.SilkS")
		)
		(fp_line
			(start -0.67945 0.3048)
			(end -0.67945 -0.305054)
			(stroke
				(width 0.1)
				(type default)
			)
			(layer "F.Fab")
		)
		(fp_line
			(start -0.12065 0.3048)
			(end -0.67945 0.3048)
			(stroke
				(width 0.1)
				(type default)
			)
			(layer "F.Fab")
		)
		(fp_line
			(start 0.120396 0.3048)
			(end 0.120396 0.2794)
			(stroke
				(width 0.1)
				(type default)
			)
			(layer "F.Fab")
		)
		(fp_line
			(start 0.67945 0.3048)
			(end 0.120396 0.3048)
			(stroke
				(width 0.1)
				(type default)
			)
			(layer "F.Fab")
		)
		(fp_line
			(start -0.12065 0.2794)
			(end -0.12065 0.3048)
			(stroke
				(width 0.1)
				(type default)
			)
			(layer "F.Fab")
		)
		(fp_line
			(start 0.120396 0.2794)
			(end -0.12065 0.2794)
			(stroke
				(width 0.1)
				(type default)
			)
			(layer "F.Fab")
		)
		(fp_line
			(start -0.12065 -0.2794)
			(end 0.12065 -0.2794)
			(stroke
				(width 0.1)
				(type default)
			)
			(layer "F.Fab")
		)
		(fp_line
			(start 0.12065 -0.2794)
			(end 0.12065 -0.3048)
			(stroke
				(width 0.1)
				(type default)
			)
			(layer "F.Fab")
		)
		(fp_line
			(start 0.12065 -0.3048)
			(end 0.67945 -0.3048)
			(stroke
				(width 0.1)
				(type default)
			)
			(layer "F.Fab")
		)
		(fp_line
			(start 0.67945 -0.3048)
			(end 0.67945 0.3048)
			(stroke
				(width 0.1)
				(type default)
			)
			(layer "F.Fab")
		)
		(fp_line
			(start -0.67945 -0.305054)
			(end -0.12065 -0.305054)
			(stroke
				(width 0.1)
				(type default)
			)
			(layer "F.Fab")
		)
		(fp_line
			(start -0.12065 -0.305054)
			(end -0.12065 -0.2794)
			(stroke
				(width 0.1)
				(type default)
			)
			(layer "F.Fab")
		)
		(pad "1" smd circle
			(at -0.40005 0 270)
			(size 0 0)
			(layers "F.Cu" "F.Mask" "F.Paste")
			(net "PEX2_MODE_SEL11")
		)
		(pad "2" smd circle
			(at 0.40005 0 270)
			(size 0 0)
			(layers "F.Cu" "F.Mask" "F.Paste")
			(net "P1V8_PEX")
		)
	)
	(footprint ""
		(layer "F.Cu")
		(at 131.642612 -162.003994 -90)
		(property "Reference" "C841"
			(at 0 0 270)
			(layer "F.SilkS")
			(hide yes)
			(effects
				(font
					(size 1.27 1.27)
				)
			)
		)
		(property "Value" ""
			(at 0 0 270)
			(layer "F.Fab")
			(effects
				(font
					(size 1.27 1.27)
				)
			)
		)
		(duplicate_pad_numbers_are_jumpers no)
		(fp_line
			(start -0.7874 0.4064)
			(end -0.7874 -0.4064)
			(stroke
				(width 0.1524)
				(type default)
			)
			(layer "F.SilkS")
		)
		(fp_line
			(start 0.7874 0.4064)
			(end -0.7874 0.4064)
			(stroke
				(width 0.1524)
				(type default)
			)
			(layer "F.SilkS")
		)
		(fp_line
			(start -0.7874 -0.4064)
			(end 0.7874 -0.4064)
			(stroke
				(width 0.1524)
				(type default)
			)
			(layer "F.SilkS")
		)
		(fp_line
			(start 0.7874 -0.4064)
			(end 0.7874 0.4064)
			(stroke
				(width 0.1524)
				(type default)
			)
			(layer "F.SilkS")
		)
		(fp_line
			(start -0.67945 0.3048)
			(end -0.67945 -0.305054)
			(stroke
				(width 0.1)
				(type default)
			)
			(layer "F.Fab")
		)
		(fp_line
			(start -0.12065 0.3048)
			(end -0.67945 0.3048)
			(stroke
				(width 0.1)
				(type default)
			)
			(layer "F.Fab")
		)
		(fp_line
			(start 0.120396 0.3048)
			(end 0.120396 0.2794)
			(stroke
				(width 0.1)
				(type default)
			)
			(layer "F.Fab")
		)
		(fp_line
			(start 0.67945 0.3048)
			(end 0.120396 0.3048)
			(stroke
				(width 0.1)
				(type default)
			)
			(layer "F.Fab")
		)
		(fp_line
			(start -0.12065 0.2794)
			(end -0.12065 0.3048)
			(stroke
				(width 0.1)
				(type default)
			)
			(layer "F.Fab")
		)
		(fp_line
			(start 0.120396 0.2794)
			(end -0.12065 0.2794)
			(stroke
				(width 0.1)
				(type default)
			)
			(layer "F.Fab")
		)
		(fp_line
			(start -0.12065 -0.2794)
			(end 0.12065 -0.2794)
			(stroke
				(width 0.1)
				(type default)
			)
			(layer "F.Fab")
		)
		(fp_line
			(start 0.12065 -0.2794)
			(end 0.12065 -0.3048)
			(stroke
				(width 0.1)
				(type default)
			)
			(layer "F.Fab")
		)
		(fp_line
			(start 0.12065 -0.3048)
			(end 0.67945 -0.3048)
			(stroke
				(width 0.1)
				(type default)
			)
			(layer "F.Fab")
		)
		(fp_line
			(start 0.67945 -0.3048)
			(end 0.67945 0.3048)
			(stroke
				(width 0.1)
				(type default)
			)
			(layer "F.Fab")
		)
		(fp_line
			(start -0.67945 -0.305054)
			(end -0.12065 -0.305054)
			(stroke
				(width 0.1)
				(type default)
			)
			(layer "F.Fab")
		)
		(fp_line
			(start -0.12065 -0.305054)
			(end -0.12065 -0.2794)
			(stroke
				(width 0.1)
				(type default)
			)
			(layer "F.Fab")
		)
		(pad "1" smd circle
			(at -0.40005 0 270)
			(size 0 0)
			(layers "F.Cu" "F.Mask" "F.Paste")
			(net "GND")
		)
		(pad "2" smd circle
			(at 0.40005 0 270)
			(size 0 0)
			(layers "F.Cu" "F.Mask" "F.Paste")
			(net "P12V_NIC2_CO_EN")
		)
	)
)
